# T6G (Grand Teton) — schematic netlist excerpt (pin names and nets, part order shuffled) for the footprints in the layout excerpt that follows; sources: Cadence DE-HDL packaged netlist, KiCad conversion of 04192023_DAF0TMB3IC0_F0TG_MB_C_brd_V02_OCP.brd

C2179  Q_CAP  100NF 50V 10% X7R  pkg C0402  page 268 : A = HSC_EN ; B = GND
C693  Q_CAP  0.1UF 25V 10% X7R  pkg 0402  page 167 : A = U124_VCC ; B = GND

(kicad_pcb
	(version 20260206)
	(generator "pcbnew")
	(generator_version "10.0")
	(general
		(thickness 1.6)
		(legacy_teardrops no)
	)
	(paper "A4")
	(title_block
		(title "04192023_DAF0TMB3IC0_F0TG_MB_C_brd_V02_OCP.brd")
		(comment 1 "Grand Teton / footprints 3737-3738 of 8354")
	)
	(layers
		(0 "F.Cu" signal "TOP")
		(4 "In1.Cu" signal "GND")
		(6 "In2.Cu" signal "IN1")
		(8 "In3.Cu" signal "GND1")
		(10 "In4.Cu" signal "IN2")
		(12 "In5.Cu" signal "GND2")
		(14 "In6.Cu" signal "IN3")
		(16 "In7.Cu" signal "GND3")
		(18 "In8.Cu" signal "VCC")
		(20 "In9.Cu" signal "VCC1")
		(22 "In10.Cu" signal "GND4")
		(24 "In11.Cu" signal "IN4")
		(26 "In12.Cu" signal "GND5")
		(28 "In13.Cu" signal "IN5")
		(30 "In14.Cu" signal "GND6")
		(32 "In15.Cu" signal "IN6")
		(34 "In16.Cu" signal "GND7")
		(2 "B.Cu" signal "BOTTOM")
		(9 "F.Adhes" user "F.Adhesive")
		(11 "B.Adhes" user "B.Adhesive")
		(13 "F.Paste" user "Package Geometry/Pastemask Top")
		(15 "B.Paste" user "Package Geometry/Pastemask Bottom")
		(5 "F.SilkS" user "Ref Des/Silkscreen Top")
		(7 "B.SilkS" user "Ref Des/Silkscreen Bottom")
		(1 "F.Mask" user "Board Geometry/Soldermask Top")
		(3 "B.Mask" user "Board Geometry/Soldermask Bottom")
		(17 "Dwgs.User" user "User.Drawings")
		(19 "Cmts.User" user "User.Comments")
		(21 "Eco1.User" user "User.Eco1")
		(23 "Eco2.User" user "User.Eco2")
		(25 "Edge.Cuts" user "Board Geometry/Outline")
		(27 "Margin" user)
		(31 "F.CrtYd" user "Package Geometry/Place Bound Top")
		(29 "B.CrtYd" user "Package Geometry/Place Bound Bottom")
		(35 "F.Fab" user "Ref Des/Assembly Top")
		(33 "B.Fab" user "Ref Des/Assembly Bottom")
	)
	(footprint ""
		(layer "F.Cu")
		(at 270.192754 -418.971476 90)
		(property "Reference" "C2179"
			(at 0 0 90)
			(layer "F.SilkS")
			(hide yes)
			(effects
				(font
					(size 1.27 1.27)
				)
			)
		)
		(property "Value" ""
			(at 0 0 90)
			(layer "F.Fab")
			(effects
				(font
					(size 1.27 1.27)
				)
			)
		)
		(duplicate_pad_numbers_are_jumpers no)
		(fp_line
			(start 0.7874 -0.4064)
			(end 0.7874 0.4064)
			(stroke
				(width 0.1524)
				(type default)
			)
			(layer "F.SilkS")
		)
		(fp_line
			(start -0.7874 -0.4064)
			(end 0.7874 -0.4064)
			(stroke
				(width 0.1524)
				(type default)
			)
			(layer "F.SilkS")
		)
		(fp_line
			(start 0.7874 0.4064)
			(end -0.7874 0.4064)
			(stroke
				(width 0.1524)
				(type default)
			)
			(layer "F.SilkS")
		)
		(fp_line
			(start -0.7874 0.4064)
			(end -0.7874 -0.4064)
			(stroke
				(width 0.1524)
				(type default)
			)
			(layer "F.SilkS")
		)
		(fp_line
			(start -0.12065 -0.305054)
			(end -0.12065 -0.2794)
			(stroke
				(width 0.1)
				(type default)
			)
			(layer "F.Fab")
		)
		(fp_line
			(start -0.67945 -0.305054)
			(end -0.12065 -0.305054)
			(stroke
				(width 0.1)
				(type default)
			)
			(layer "F.Fab")
		)
		(fp_line
			(start 0.67945 -0.3048)
			(end 0.67945 0.3048)
			(stroke
				(width 0.1)
				(type default)
			)
			(layer "F.Fab")
		)
		(fp_line
			(start 0.12065 -0.3048)
			(end 0.67945 -0.3048)
			(stroke
				(width 0.1)
				(type default)
			)
			(layer "F.Fab")
		)
		(fp_line
			(start 0.12065 -0.2794)
			(end 0.12065 -0.3048)
			(stroke
				(width 0.1)
				(type default)
			)
			(layer "F.Fab")
		)
		(fp_line
			(start -0.12065 -0.2794)
			(end 0.12065 -0.2794)
			(stroke
				(width 0.1)
				(type default)
			)
			(layer "F.Fab")
		)
		(fp_line
			(start 0.120396 0.2794)
			(end -0.12065 0.2794)
			(stroke
				(width 0.1)
				(type default)
			)
			(layer "F.Fab")
		)
		(fp_line
			(start -0.12065 0.2794)
			(end -0.12065 0.3048)
			(stroke
				(width 0.1)
				(type default)
			)
			(layer "F.Fab")
		)
		(fp_line
			(start 0.67945 0.3048)
			(end 0.120396 0.3048)
			(stroke
				(width 0.1)
				(type default)
			)
			(layer "F.Fab")
		)
		(fp_line
			(start 0.120396 0.3048)
			(end 0.120396 0.2794)
			(stroke
				(width 0.1)
				(type default)
			)
			(layer "F.Fab")
		)
		(fp_line
			(start -0.12065 0.3048)
			(end -0.67945 0.3048)
			(stroke
				(width 0.1)
				(type default)
			)
			(layer "F.Fab")
		)
		(fp_line
			(start -0.67945 0.3048)
			(end -0.67945 -0.305054)
			(stroke
				(width 0.1)
				(type default)
			)
			(layer "F.Fab")
		)
		(pad "1" smd circle
			(at -0.40005 0 90)
			(size 0 0)
			(layers "F.Cu" "F.Mask" "F.Paste")
			(net "HSC_EN")
		)
		(pad "2" smd circle
			(at 0.40005 0 90)
			(size 0 0)
			(layers "F.Cu" "F.Mask" "F.Paste")
			(net "GND")
		)
	)
	(footprint ""
		(layer "F.Cu")
		(at 427.975268 -58.397648 90)
		(property "Reference" "C693"
			(at 0 0 90)
			(layer "F.SilkS")
			(hide yes)
			(effects
				(font
					(size 1.27 1.27)
				)
			)
		)
		(property "Value" ""
			(at 0 0 90)
			(layer "F.Fab")
			(effects
				(font
					(size 1.27 1.27)
				)
			)
		)
		(duplicate_pad_numbers_are_jumpers no)
		(fp_line
			(start 0.7874 -0.4064)
			(end 0.7874 0.4064)
			(stroke
				(width 0.1524)
				(type default)
			)
			(layer "F.SilkS")
		)
		(fp_line
			(start -0.7874 -0.4064)
			(end 0.7874 -0.4064)
			(stroke
				(width 0.1524)
				(type default)
			)
			(layer "F.SilkS")
		)
		(fp_line
			(start 0.7874 0.4064)
			(end -0.7874 0.4064)
			(stroke
				(width 0.1524)
				(type default)
			)
			(layer "F.SilkS")
		)
		(fp_line
			(start -0.7874 0.4064)
			(end -0.7874 -0.4064)
			(stroke
				(width 0.1524)
				(type default)
			)
			(layer "F.SilkS")
		)
		(fp_line
			(start -0.12065 -0.305054)
			(end -0.12065 -0.2794)
			(stroke
				(width 0.1)
				(type default)
			)
			(layer "F.Fab")
		)
		(fp_line
			(start -0.67945 -0.305054)
			(end -0.12065 -0.305054)
			(stroke
				(width 0.1)
				(type default)
			)
			(layer "F.Fab")
		)
		(fp_line
			(start 0.67945 -0.3048)
			(end 0.67945 0.3048)
			(stroke
				(width 0.1)
				(type default)
			)
			(layer "F.Fab")
		)
		(fp_line
			(start 0.12065 -0.3048)
			(end 0.67945 -0.3048)
			(stroke
				(width 0.1)
				(type default)
			)
			(layer "F.Fab")
		)
		(fp_line
			(start 0.12065 -0.2794)
			(end 0.12065 -0.3048)
			(stroke
				(width 0.1)
				(type default)
			)
			(layer "F.Fab")
		)
		(fp_line
			(start -0.12065 -0.2794)
			(end 0.12065 -0.2794)
			(stroke
				(width 0.1)
				(type default)
			)
			(layer "F.Fab")
		)
		(fp_line
			(start 0.120396 0.2794)
			(end -0.12065 0.2794)
			(stroke
				(width 0.1)
				(type default)
			)
			(layer "F.Fab")
		)
		(fp_line
			(start -0.12065 0.2794)
			(end -0.12065 0.3048)
			(stroke
				(width 0.1)
				(type default)
			)
			(layer "F.Fab")
		)
		(fp_line
			(start 0.67945 0.3048)
			(end 0.120396 0.3048)
			(stroke
				(width 0.1)
				(type default)
			)
			(layer "F.Fab")
		)
		(fp_line
			(start 0.120396 0.3048)
			(end 0.120396 0.2794)
			(stroke
				(width 0.1)
				(type default)
			)
			(layer "F.Fab")
		)
		(fp_line
			(start -0.12065 0.3048)
			(end -0.67945 0.3048)
			(stroke
				(width 0.1)
				(type default)
			)
			(layer "F.Fab")
		)
		(fp_line
			(start -0.67945 0.3048)
			(end -0.67945 -0.305054)
			(stroke
				(width 0.1)
				(type default)
			)
			(layer "F.Fab")
		)
		(pad "1" smd circle
			(at -0.40005 0 90)
			(size 0 0)
			(layers "F.Cu" "F.Mask" "F.Paste")
			(net "U124_VCC")
		)
		(pad "2" smd circle
			(at 0.40005 0 90)
			(size 0 0)
			(layers "F.Cu" "F.Mask" "F.Paste")
			(net "GND")
		)
	)
)
